(kicad_pcb
	(version 20260206)
	(generator "pcbnew")
	(generator_version "10.0")
	(general
		(thickness 1.6)
		(legacy_teardrops no)
	)
	(paper "A4")
	(title_block
		(title "04192023_DAF0TMB3IC0_F0TG_MB_C_brd_V02_OCP.brd")
		(comment 1 "Grand Teton / footprints 719-725 of 8354")
	)
	(layers
		(0 "F.Cu" signal "TOP")
		(4 "In1.Cu" signal "GND")
		(6 "In2.Cu" signal "IN1")
		(8 "In3.Cu" signal "GND1")
		(10 "In4.Cu" signal "IN2")
		(12 "In5.Cu" signal "GND2")
		(14 "In6.Cu" signal "IN3")
		(16 "In7.Cu" signal "GND3")
		(18 "In8.Cu" signal "VCC")
		(20 "In9.Cu" signal "VCC1")
		(22 "In10.Cu" signal "GND4")
		(24 "In11.Cu" signal "IN4")
		(26 "In12.Cu" signal "GND5")
		(28 "In13.Cu" signal "IN5")
		(30 "In14.Cu" signal "GND6")
		(32 "In15.Cu" signal "IN6")
		(34 "In16.Cu" signal "GND7")
		(2 "B.Cu" signal "BOTTOM")
		(9 "F.Adhes" user "F.Adhesive")
		(11 "B.Adhes" user "B.Adhesive")
		(13 "F.Paste" user "Package Geometry/Pastemask Top")
		(15 "B.Paste" user "Package Geometry/Pastemask Bottom")
		(5 "F.SilkS" user "Ref Des/Silkscreen Top")
		(7 "B.SilkS" user "Ref Des/Silkscreen Bottom")
		(1 "F.Mask" user "Board Geometry/Soldermask Top")
		(3 "B.Mask" user "Board Geometry/Soldermask Bottom")
		(17 "Dwgs.User" user "User.Drawings")
		(19 "Cmts.User" user "User.Comments")
		(21 "Eco1.User" user "User.Eco1")
		(23 "Eco2.User" user "User.Eco2")
		(25 "Edge.Cuts" user "Board Geometry/Outline")
		(27 "Margin" user)
		(31 "F.CrtYd" user "Package Geometry/Place Bound Top")
		(29 "B.CrtYd" user "Package Geometry/Place Bound Bottom")
		(35 "F.Fab" user "Ref Des/Assembly Top")
		(33 "B.Fab" user "Ref Des/Assembly Bottom")
	)
	(footprint ""
		(layer "F.Cu")
		(at 120.396 -420.497)
		(property "Reference" "R3431"
			(at 0 0 0)
			(layer "F.SilkS")
			(hide yes)
			(effects
				(font
					(size 1.27 1.27)
				)
			)
		)
		(property "Value" ""
			(at 0 0 0)
			(layer "F.Fab")
			(effects
				(font
					(size 1.27 1.27)
				)
			)
		)
		(duplicate_pad_numbers_are_jumpers no)
		(fp_line
			(start -0.7874 -0.4064)
			(end 0.7874 -0.4064)
			(stroke
				(width 0.1524)
				(type default)
			)
			(layer "F.SilkS")
		)
		(fp_line
			(start -0.7874 0.4064)
			(end -0.7874 -0.4064)
			(stroke
				(width 0.1524)
				(type default)
			)
			(layer "F.SilkS")
		)
		(fp_line
			(start 0.7874 -0.4064)
			(end 0.7874 0.4064)
			(stroke
				(width 0.1524)
				(type default)
			)
			(layer "F.SilkS")
		)
		(fp_line
			(start 0.7874 0.4064)
			(end -0.7874 0.4064)
			(stroke
				(width 0.1524)
				(type default)
			)
			(layer "F.SilkS")
		)
		(fp_line
			(start -0.67945 -0.305054)
			(end -0.12065 -0.305054)
			(stroke
				(width 0.1)
				(type default)
			)
			(layer "F.Fab")
		)
		(fp_line
			(start -0.67945 0.3048)
			(end -0.67945 -0.305054)
			(stroke
				(width 0.1)
				(type default)
			)
			(layer "F.Fab")
		)
		(fp_line
			(start -0.12065 -0.305054)
			(end -0.12065 -0.2794)
			(stroke
				(width 0.1)
				(type default)
			)
			(layer "F.Fab")
		)
		(fp_line
			(start -0.12065 -0.2794)
			(end 0.12065 -0.2794)
			(stroke
				(width 0.1)
				(type default)
			)
			(layer "F.Fab")
		)
		(fp_line
			(start -0.12065 0.2794)
			(end -0.12065 0.3048)
			(stroke
				(width 0.1)
				(type default)
			)
			(layer "F.Fab")
		)
		(fp_line
			(start -0.12065 0.3048)
			(end -0.67945 0.3048)
			(stroke
				(width 0.1)
				(type default)
			)
			(layer "F.Fab")
		)
		(fp_line
			(start 0.120396 0.2794)
			(end -0.12065 0.2794)
			(stroke
				(width 0.1)
				(type default)
			)
			(layer "F.Fab")
		)
		(fp_line
			(start 0.120396 0.3048)
			(end 0.120396 0.2794)
			(stroke
				(width 0.1)
				(type default)
			)
			(layer "F.Fab")
		)
		(fp_line
			(start 0.12065 -0.3048)
			(end 0.67945 -0.3048)
			(stroke
				(width 0.1)
				(type default)
			)
			(layer "F.Fab")
		)
		(fp_line
			(start 0.12065 -0.2794)
			(end 0.12065 -0.3048)
			(stroke
				(width 0.1)
				(type default)
			)
			(layer "F.Fab")
		)
		(fp_line
			(start 0.67945 -0.3048)
			(end 0.67945 0.3048)
			(stroke
				(width 0.1)
				(type default)
			)
			(layer "F.Fab")
		)
		(fp_line
			(start 0.67945 0.3048)
			(end 0.120396 0.3048)
			(stroke
				(width 0.1)
				(type default)
			)
			(layer "F.Fab")
		)
		(pad "1" smd circle
			(at -0.40005 0)
			(size 0 0)
			(layers "F.Cu" "F.Mask" "F.Paste")
			(net "GPU_HMC_PRSNT_N")
		)
		(pad "2" smd circle
			(at 0.40005 0)
			(size 0 0)
			(layers "F.Cu" "F.Mask" "F.Paste")
			(net "GND")
		)
	)
	(footprint ""
		(layer "F.Cu")
		(at 313.313064 -346.863924 -90)
		(property "Reference" "PC115_4"
			(at 0 0 270)
			(layer "F.SilkS")
			(hide yes)
			(effects
				(font
					(size 1.27 1.27)
				)
			)
		)
		(property "Value" ""
			(at 0 0 270)
			(layer "F.Fab")
			(effects
				(font
					(size 1.27 1.27)
				)
			)
		)
		(duplicate_pad_numbers_are_jumpers no)
		(fp_line
			(start -0.7874 0.4064)
			(end -0.7874 -0.4064)
			(stroke
				(width 0.1524)
				(type default)
			)
			(layer "F.SilkS")
		)
		(fp_line
			(start 0.7874 0.4064)
			(end -0.7874 0.4064)
			(stroke
				(width 0.1524)
				(type default)
			)
			(layer "F.SilkS")
		)
		(fp_line
			(start -0.7874 -0.4064)
			(end 0.7874 -0.4064)
			(stroke
				(width 0.1524)
				(type default)
			)
			(layer "F.SilkS")
		)
		(fp_line
			(start 0.7874 -0.4064)
			(end 0.7874 0.4064)
			(stroke
				(width 0.1524)
				(type default)
			)
			(layer "F.SilkS")
		)
		(fp_line
			(start -0.67945 0.3048)
			(end -0.67945 -0.305054)
			(stroke
				(width 0.1)
				(type default)
			)
			(layer "F.Fab")
		)
		(fp_line
			(start -0.12065 0.3048)
			(end -0.67945 0.3048)
			(stroke
				(width 0.1)
				(type default)
			)
			(layer "F.Fab")
		)
		(fp_line
			(start 0.120396 0.3048)
			(end 0.120396 0.2794)
			(stroke
				(width 0.1)
				(type default)
			)
			(layer "F.Fab")
		)
		(fp_line
			(start 0.67945 0.3048)
			(end 0.120396 0.3048)
			(stroke
				(width 0.1)
				(type default)
			)
			(layer "F.Fab")
		)
		(fp_line
			(start -0.12065 0.2794)
			(end -0.12065 0.3048)
			(stroke
				(width 0.1)
				(type default)
			)
			(layer "F.Fab")
		)
		(fp_line
			(start 0.120396 0.2794)
			(end -0.12065 0.2794)
			(stroke
				(width 0.1)
				(type default)
			)
			(layer "F.Fab")
		)
		(fp_line
			(start -0.12065 -0.2794)
			(end 0.12065 -0.2794)
			(stroke
				(width 0.1)
				(type default)
			)
			(layer "F.Fab")
		)
		(fp_line
			(start 0.12065 -0.2794)
			(end 0.12065 -0.3048)
			(stroke
				(width 0.1)
				(type default)
			)
			(layer "F.Fab")
		)
		(fp_line
			(start 0.12065 -0.3048)
			(end 0.67945 -0.3048)
			(stroke
				(width 0.1)
				(type default)
			)
			(layer "F.Fab")
		)
		(fp_line
			(start 0.67945 -0.3048)
			(end 0.67945 0.3048)
			(stroke
				(width 0.1)
				(type default)
			)
			(layer "F.Fab")
		)
		(fp_line
			(start -0.67945 -0.305054)
			(end -0.12065 -0.305054)
			(stroke
				(width 0.1)
				(type default)
			)
			(layer "F.Fab")
		)
		(fp_line
			(start -0.12065 -0.305054)
			(end -0.12065 -0.2794)
			(stroke
				(width 0.1)
				(type default)
			)
			(layer "F.Fab")
		)
		(pad "1" smd circle
			(at -0.40005 0 270)
			(size 0 0)
			(layers "F.Cu" "F.Mask" "F.Paste")
			(net "SW_P12V_AUX_PVDDCR_CPU1_P0_FLT")
		)
		(pad "2" smd circle
			(at 0.40005 0 270)
			(size 0 0)
			(layers "F.Cu" "F.Mask" "F.Paste")
			(net "GND")
		)
	)
	(footprint ""
		(layer "F.Cu")
		(at 223.70288 -43.525948)
		(property "Reference" "R3533"
			(at 0 0 0)
			(layer "F.SilkS")
			(hide yes)
			(effects
				(font
					(size 1.27 1.27)
				)
			)
		)
		(property "Value" ""
			(at 0 0 0)
			(layer "F.Fab")
			(effects
				(font
					(size 1.27 1.27)
				)
			)
		)
		(duplicate_pad_numbers_are_jumpers no)
		(fp_line
			(start -0.7874 -0.4064)
			(end 0.7874 -0.4064)
			(stroke
				(width 0.1524)
				(type default)
			)
			(layer "F.SilkS")
		)
		(fp_line
			(start -0.7874 0.4064)
			(end -0.7874 -0.4064)
			(stroke
				(width 0.1524)
				(type default)
			)
			(layer "F.SilkS")
		)
		(fp_line
			(start 0.7874 -0.4064)
			(end 0.7874 0.4064)
			(stroke
				(width 0.1524)
				(type default)
			)
			(layer "F.SilkS")
		)
		(fp_line
			(start 0.7874 0.4064)
			(end -0.7874 0.4064)
			(stroke
				(width 0.1524)
				(type default)
			)
			(layer "F.SilkS")
		)
		(fp_line
			(start -0.67945 -0.305054)
			(end -0.12065 -0.305054)
			(stroke
				(width 0.1)
				(type default)
			)
			(layer "F.Fab")
		)
		(fp_line
			(start -0.67945 0.3048)
			(end -0.67945 -0.305054)
			(stroke
				(width 0.1)
				(type default)
			)
			(layer "F.Fab")
		)
		(fp_line
			(start -0.12065 -0.305054)
			(end -0.12065 -0.2794)
			(stroke
				(width 0.1)
				(type default)
			)
			(layer "F.Fab")
		)
		(fp_line
			(start -0.12065 -0.2794)
			(end 0.12065 -0.2794)
			(stroke
				(width 0.1)
				(type default)
			)
			(layer "F.Fab")
		)
		(fp_line
			(start -0.12065 0.2794)
			(end -0.12065 0.3048)
			(stroke
				(width 0.1)
				(type default)
			)
			(layer "F.Fab")
		)
		(fp_line
			(start -0.12065 0.3048)
			(end -0.67945 0.3048)
			(stroke
				(width 0.1)
				(type default)
			)
			(layer "F.Fab")
		)
		(fp_line
			(start 0.120396 0.2794)
			(end -0.12065 0.2794)
			(stroke
				(width 0.1)
				(type default)
			)
			(layer "F.Fab")
		)
		(fp_line
			(start 0.120396 0.3048)
			(end 0.120396 0.2794)
			(stroke
				(width 0.1)
				(type default)
			)
			(layer "F.Fab")
		)
		(fp_line
			(start 0.12065 -0.3048)
			(end 0.67945 -0.3048)
			(stroke
				(width 0.1)
				(type default)
			)
			(layer "F.Fab")
		)
		(fp_line
			(start 0.12065 -0.2794)
			(end 0.12065 -0.3048)
			(stroke
				(width 0.1)
				(type default)
			)
			(layer "F.Fab")
		)
		(fp_line
			(start 0.67945 -0.3048)
			(end 0.67945 0.3048)
			(stroke
				(width 0.1)
				(type default)
			)
			(layer "F.Fab")
		)
		(fp_line
			(start 0.67945 0.3048)
			(end 0.120396 0.3048)
			(stroke
				(width 0.1)
				(type default)
			)
			(layer "F.Fab")
		)
		(pad "1" smd circle
			(at -0.40005 0)
			(size 0 0)
			(layers "F.Cu" "F.Mask" "F.Paste")
			(net "SMB_E1S_3V3AUX_ISO_SCL_R")
		)
		(pad "2" smd circle
			(at 0.40005 0)
			(size 0 0)
			(layers "F.Cu" "F.Mask" "F.Paste")
			(net "SMB_E1S_3V3AUX_ISO_SCL")
		)
	)
	(footprint ""
		(layer "F.Cu")
		(at 183.364886 -427.449234 -90)
		(property "Reference" "R9019"
			(at 0 0 270)
			(layer "F.SilkS")
			(hide yes)
			(effects
				(font
					(size 1.27 1.27)
				)
			)
		)
		(property "Value" ""
			(at 0 0 270)
			(layer "F.Fab")
			(effects
				(font
					(size 1.27 1.27)
				)
			)
		)
		(duplicate_pad_numbers_are_jumpers no)
		(fp_line
			(start -0.7874 0.4064)
			(end -0.7874 -0.4064)
			(stroke
				(width 0.1524)
				(type default)
			)
			(layer "F.SilkS")
		)
		(fp_line
			(start 0.7874 0.4064)
			(end -0.7874 0.4064)
			(stroke
				(width 0.1524)
				(type default)
			)
			(layer "F.SilkS")
		)
		(fp_line
			(start -0.7874 -0.4064)
			(end 0.7874 -0.4064)
			(stroke
				(width 0.1524)
				(type default)
			)
			(layer "F.SilkS")
		)
		(fp_line
			(start 0.7874 -0.4064)
			(end 0.7874 0.4064)
			(stroke
				(width 0.1524)
				(type default)
			)
			(layer "F.SilkS")
		)
		(fp_line
			(start -0.67945 0.3048)
			(end -0.67945 -0.305054)
			(stroke
				(width 0.1)
				(type default)
			)
			(layer "F.Fab")
		)
		(fp_line
			(start -0.12065 0.3048)
			(end -0.67945 0.3048)
			(stroke
				(width 0.1)
				(type default)
			)
			(layer "F.Fab")
		)
		(fp_line
			(start 0.120396 0.3048)
			(end 0.120396 0.2794)
			(stroke
				(width 0.1)
				(type default)
			)
			(layer "F.Fab")
		)
		(fp_line
			(start 0.67945 0.3048)
			(end 0.120396 0.3048)
			(stroke
				(width 0.1)
				(type default)
			)
			(layer "F.Fab")
		)
		(fp_line
			(start -0.12065 0.2794)
			(end -0.12065 0.3048)
			(stroke
				(width 0.1)
				(type default)
			)
			(layer "F.Fab")
		)
		(fp_line
			(start 0.120396 0.2794)
			(end -0.12065 0.2794)
			(stroke
				(width 0.1)
				(type default)
			)
			(layer "F.Fab")
		)
		(fp_line
			(start -0.12065 -0.2794)
			(end 0.12065 -0.2794)
			(stroke
				(width 0.1)
				(type default)
			)
			(layer "F.Fab")
		)
		(fp_line
			(start 0.12065 -0.2794)
			(end 0.12065 -0.3048)
			(stroke
				(width 0.1)
				(type default)
			)
			(layer "F.Fab")
		)
		(fp_line
			(start 0.12065 -0.3048)
			(end 0.67945 -0.3048)
			(stroke
				(width 0.1)
				(type default)
			)
			(layer "F.Fab")
		)
		(fp_line
			(start 0.67945 -0.3048)
			(end 0.67945 0.3048)
			(stroke
				(width 0.1)
				(type default)
			)
			(layer "F.Fab")
		)
		(fp_line
			(start -0.67945 -0.305054)
			(end -0.12065 -0.305054)
			(stroke
				(width 0.1)
				(type default)
			)
			(layer "F.Fab")
		)
		(fp_line
			(start -0.12065 -0.305054)
			(end -0.12065 -0.2794)
			(stroke
				(width 0.1)
				(type default)
			)
			(layer "F.Fab")
		)
		(pad "1" smd circle
			(at -0.40005 0 270)
			(size 0 0)
			(layers "F.Cu" "F.Mask" "F.Paste")
			(net "PRSNT_CABLE_GPU_A1_ISO_N")
		)
		(pad "2" smd circle
			(at 0.40005 0 270)
			(size 0 0)
			(layers "F.Cu" "F.Mask" "F.Paste")
			(net "PRSNT_CABLE_GPU_A1_ISO_R1_N")
		)
	)
	(footprint ""
		(layer "F.Cu")
		(at 353.9236 -407.8732 90)
		(property "Reference" "R1473"
			(at 0 0 90)
			(layer "F.SilkS")
			(hide yes)
			(effects
				(font
					(size 1.27 1.27)
				)
			)
		)
		(property "Value" ""
			(at 0 0 90)
			(layer "F.Fab")
			(effects
				(font
					(size 1.27 1.27)
				)
			)
		)
		(duplicate_pad_numbers_are_jumpers no)
		(fp_line
			(start 0.32512 -0.175006)
			(end 0.32512 0.175006)
			(stroke
				(width 0.1)
				(type default)
			)
			(layer "F.Fab")
		)
		(fp_line
			(start -0.32512 -0.175006)
			(end 0.32512 -0.175006)
			(stroke
				(width 0.1)
				(type default)
			)
			(layer "F.Fab")
		)
		(fp_line
			(start 0.32512 0.175006)
			(end -0.32512 0.175006)
			(stroke
				(width 0.1)
				(type default)
			)
			(layer "F.Fab")
		)
		(fp_line
			(start -0.32512 0.175006)
			(end -0.32512 -0.175006)
			(stroke
				(width 0.1)
				(type default)
			)
			(layer "F.Fab")
		)
		(pad "1" smd rect
			(at -0.2667 0 90)
			(size 0.3048 0.381)
			(layers "F.Cu" "F.Mask" "F.Paste")
			(net "P1V8_CPU0_RT_1D")
		)
		(pad "2" smd rect
			(at 0.2667 0 270)
			(size 0.3048 0.381)
			(layers "F.Cu" "F.Mask" "F.Paste")
			(net "JTAG_TCK_RT_CPU0_P1")
		)
	)
	(footprint ""
		(layer "F.Cu")
		(at 251.474224 -132.337556)
		(property "Reference" "R20"
			(at 0 0 0)
			(layer "F.SilkS")
			(hide yes)
			(effects
				(font
					(size 1.27 1.27)
				)
			)
		)
		(property "Value" ""
			(at 0 0 0)
			(layer "F.Fab")
			(effects
				(font
					(size 1.27 1.27)
				)
			)
		)
		(duplicate_pad_numbers_are_jumpers no)
		(fp_line
			(start -0.7874 -0.4064)
			(end 0.7874 -0.4064)
			(stroke
				(width 0.1524)
				(type default)
			)
			(layer "F.SilkS")
		)
		(fp_line
			(start -0.7874 0.4064)
			(end -0.7874 -0.4064)
			(stroke
				(width 0.1524)
				(type default)
			)
			(layer "F.SilkS")
		)
		(fp_line
			(start 0.7874 -0.4064)
			(end 0.7874 0.4064)
			(stroke
				(width 0.1524)
				(type default)
			)
			(layer "F.SilkS")
		)
		(fp_line
			(start 0.7874 0.4064)
			(end -0.7874 0.4064)
			(stroke
				(width 0.1524)
				(type default)
			)
			(layer "F.SilkS")
		)
		(fp_line
			(start -0.67945 -0.305054)
			(end -0.12065 -0.305054)
			(stroke
				(width 0.1)
				(type default)
			)
			(layer "F.Fab")
		)
		(fp_line
			(start -0.67945 0.3048)
			(end -0.67945 -0.305054)
			(stroke
				(width 0.1)
				(type default)
			)
			(layer "F.Fab")
		)
		(fp_line
			(start -0.12065 -0.305054)
			(end -0.12065 -0.2794)
			(stroke
				(width 0.1)
				(type default)
			)
			(layer "F.Fab")
		)
		(fp_line
			(start -0.12065 -0.2794)
			(end 0.12065 -0.2794)
			(stroke
				(width 0.1)
				(type default)
			)
			(layer "F.Fab")
		)
		(fp_line
			(start -0.12065 0.2794)
			(end -0.12065 0.3048)
			(stroke
				(width 0.1)
				(type default)
			)
			(layer "F.Fab")
		)
		(fp_line
			(start -0.12065 0.3048)
			(end -0.67945 0.3048)
			(stroke
				(width 0.1)
				(type default)
			)
			(layer "F.Fab")
		)
		(fp_line
			(start 0.120396 0.2794)
			(end -0.12065 0.2794)
			(stroke
				(width 0.1)
				(type default)
			)
			(layer "F.Fab")
		)
		(fp_line
			(start 0.120396 0.3048)
			(end 0.120396 0.2794)
			(stroke
				(width 0.1)
				(type default)
			)
			(layer "F.Fab")
		)
		(fp_line
			(start 0.12065 -0.3048)
			(end 0.67945 -0.3048)
			(stroke
				(width 0.1)
				(type default)
			)
			(layer "F.Fab")
		)
		(fp_line
			(start 0.12065 -0.2794)
			(end 0.12065 -0.3048)
			(stroke
				(width 0.1)
				(type default)
			)
			(layer "F.Fab")
		)
		(fp_line
			(start 0.67945 -0.3048)
			(end 0.67945 0.3048)
			(stroke
				(width 0.1)
				(type default)
			)
			(layer "F.Fab")
		)
		(fp_line
			(start 0.67945 0.3048)
			(end 0.120396 0.3048)
			(stroke
				(width 0.1)
				(type default)
			)
			(layer "F.Fab")
		)
		(pad "1" smd circle
			(at -0.40005 0)
			(size 0 0)
			(layers "F.Cu" "F.Mask" "F.Paste")
			(net "P3V3_AUX")
		)
		(pad "2" smd circle
			(at 0.40005 0)
			(size 0 0)
			(layers "F.Cu" "F.Mask" "F.Paste")
			(net "SPI_CPU0_LVC3_SCM_CLK")
		)
	)
	(footprint ""
		(layer "F.Cu")
		(at 346.968572 -156.487622 -90)
		(property "Reference" "PR432"
			(at 0 0 270)
			(layer "F.SilkS")
			(hide yes)
			(effects
				(font
					(size 1.27 1.27)
				)
			)
		)
		(property "Value" ""
			(at 0 0 270)
			(layer "F.Fab")
			(effects
				(font
					(size 1.27 1.27)
				)
			)
		)
		(duplicate_pad_numbers_are_jumpers no)
		(fp_line
			(start -0.7874 0.4064)
			(end -0.7874 -0.4064)
			(stroke
				(width 0.1524)
				(type default)
			)
			(layer "F.SilkS")
		)
		(fp_line
			(start 0.7874 0.4064)
			(end -0.7874 0.4064)
			(stroke
				(width 0.1524)
				(type default)
			)
			(layer "F.SilkS")
		)
		(fp_line
			(start -0.7874 -0.4064)
			(end 0.7874 -0.4064)
			(stroke
				(width 0.1524)
				(type default)
			)
			(layer "F.SilkS")
		)
		(fp_line
			(start 0.7874 -0.4064)
			(end 0.7874 0.4064)
			(stroke
				(width 0.1524)
				(type default)
			)
			(layer "F.SilkS")
		)
		(fp_line
			(start -0.67945 0.3048)
			(end -0.67945 -0.305054)
			(stroke
				(width 0.1)
				(type default)
			)
			(layer "F.Fab")
		)
		(fp_line
			(start -0.12065 0.3048)
			(end -0.67945 0.3048)
			(stroke
				(width 0.1)
				(type default)
			)
			(layer "F.Fab")
		)
		(fp_line
			(start 0.120396 0.3048)
			(end 0.120396 0.2794)
			(stroke
				(width 0.1)
				(type default)
			)
			(layer "F.Fab")
		)
		(fp_line
			(start 0.67945 0.3048)
			(end 0.120396 0.3048)
			(stroke
				(width 0.1)
				(type default)
			)
			(layer "F.Fab")
		)
		(fp_line
			(start -0.12065 0.2794)
			(end -0.12065 0.3048)
			(stroke
				(width 0.1)
				(type default)
			)
			(layer "F.Fab")
		)
		(fp_line
			(start 0.120396 0.2794)
			(end -0.12065 0.2794)
			(stroke
				(width 0.1)
				(type default)
			)
			(layer "F.Fab")
		)
		(fp_line
			(start -0.12065 -0.2794)
			(end 0.12065 -0.2794)
			(stroke
				(width 0.1)
				(type default)
			)
			(layer "F.Fab")
		)
		(fp_line
			(start 0.12065 -0.2794)
			(end 0.12065 -0.3048)
			(stroke
				(width 0.1)
				(type default)
			)
			(layer "F.Fab")
		)
		(fp_line
			(start 0.12065 -0.3048)
			(end 0.67945 -0.3048)
			(stroke
				(width 0.1)
				(type default)
			)
			(layer "F.Fab")
		)
		(fp_line
			(start 0.67945 -0.3048)
			(end 0.67945 0.3048)
			(stroke
				(width 0.1)
				(type default)
			)
			(layer "F.Fab")
		)
		(fp_line
			(start -0.67945 -0.305054)
			(end -0.12065 -0.305054)
			(stroke
				(width 0.1)
				(type default)
			)
			(layer "F.Fab")
		)
		(fp_line
			(start -0.12065 -0.305054)
			(end -0.12065 -0.2794)
			(stroke
				(width 0.1)
				(type default)
			)
			(layer "F.Fab")
		)
		(pad "1" smd circle
			(at -0.40005 0 270)
			(size 0 0)
			(layers "F.Cu" "F.Mask" "F.Paste")
			(net "SW_PVDDCR_CPU0_P0_BOOT6")
		)
		(pad "2" smd circle
			(at 0.40005 0 270)
			(size 0 0)
			(layers "F.Cu" "F.Mask" "F.Paste")
			(net "SW_PVDDCR_CPU0_P0_BOOT6_RC")
		)
	)
)
